(kicad_pcb
	(version 20260206)
	(generator "pcbnew")
	(generator_version "10.0")
	(general
		(thickness 1.6)
		(legacy_teardrops no)
	)
	(paper "A4")
	(title_block
		(title "04192023_DAF0TMB3IC0_F0TG_MB_C_brd_V02_OCP.brd")
		(comment 1 "Grand Teton / footprints 2549-2553 of 8354")
	)
	(layers
		(0 "F.Cu" signal "TOP")
		(4 "In1.Cu" signal "GND")
		(6 "In2.Cu" signal "IN1")
		(8 "In3.Cu" signal "GND1")
		(10 "In4.Cu" signal "IN2")
		(12 "In5.Cu" signal "GND2")
		(14 "In6.Cu" signal "IN3")
		(16 "In7.Cu" signal "GND3")
		(18 "In8.Cu" signal "VCC")
		(20 "In9.Cu" signal "VCC1")
		(22 "In10.Cu" signal "GND4")
		(24 "In11.Cu" signal "IN4")
		(26 "In12.Cu" signal "GND5")
		(28 "In13.Cu" signal "IN5")
		(30 "In14.Cu" signal "GND6")
		(32 "In15.Cu" signal "IN6")
		(34 "In16.Cu" signal "GND7")
		(2 "B.Cu" signal "BOTTOM")
		(9 "F.Adhes" user "F.Adhesive")
		(11 "B.Adhes" user "B.Adhesive")
		(13 "F.Paste" user "Package Geometry/Pastemask Top")
		(15 "B.Paste" user "Package Geometry/Pastemask Bottom")
		(5 "F.SilkS" user "Ref Des/Silkscreen Top")
		(7 "B.SilkS" user "Ref Des/Silkscreen Bottom")
		(1 "F.Mask" user "Board Geometry/Soldermask Top")
		(3 "B.Mask" user "Board Geometry/Soldermask Bottom")
		(17 "Dwgs.User" user "User.Drawings")
		(19 "Cmts.User" user "User.Comments")
		(21 "Eco1.User" user "User.Eco1")
		(23 "Eco2.User" user "User.Eco2")
		(25 "Edge.Cuts" user "Board Geometry/Outline")
		(27 "Margin" user)
		(31 "F.CrtYd" user "Package Geometry/Place Bound Top")
		(29 "B.CrtYd" user "Package Geometry/Place Bound Bottom")
		(35 "F.Fab" user "Ref Des/Assembly Top")
		(33 "B.Fab" user "Ref Des/Assembly Bottom")
	)
	(footprint ""
		(layer "F.Cu")
		(at 448.672458 -92.493592 180)
		(property "Reference" "R3616"
			(at 0 0 180)
			(layer "F.SilkS")
			(hide yes)
			(effects
				(font
					(size 1.27 1.27)
				)
			)
		)
		(property "Value" ""
			(at 0 0 180)
			(layer "F.Fab")
			(effects
				(font
					(size 1.27 1.27)
				)
			)
		)
		(duplicate_pad_numbers_are_jumpers no)
		(fp_line
			(start 0.7874 0.4064)
			(end -0.7874 0.4064)
			(stroke
				(width 0.1524)
				(type default)
			)
			(layer "F.SilkS")
		)
		(fp_line
			(start 0.7874 -0.4064)
			(end 0.7874 0.4064)
			(stroke
				(width 0.1524)
				(type default)
			)
			(layer "F.SilkS")
		)
		(fp_line
			(start -0.7874 0.4064)
			(end -0.7874 -0.4064)
			(stroke
				(width 0.1524)
				(type default)
			)
			(layer "F.SilkS")
		)
		(fp_line
			(start -0.7874 -0.4064)
			(end 0.7874 -0.4064)
			(stroke
				(width 0.1524)
				(type default)
			)
			(layer "F.SilkS")
		)
		(fp_line
			(start 0.67945 0.3048)
			(end 0.120396 0.3048)
			(stroke
				(width 0.1)
				(type default)
			)
			(layer "F.Fab")
		)
		(fp_line
			(start 0.67945 -0.3048)
			(end 0.67945 0.3048)
			(stroke
				(width 0.1)
				(type default)
			)
			(layer "F.Fab")
		)
		(fp_line
			(start 0.12065 -0.2794)
			(end 0.12065 -0.3048)
			(stroke
				(width 0.1)
				(type default)
			)
			(layer "F.Fab")
		)
		(fp_line
			(start 0.12065 -0.3048)
			(end 0.67945 -0.3048)
			(stroke
				(width 0.1)
				(type default)
			)
			(layer "F.Fab")
		)
		(fp_line
			(start 0.120396 0.3048)
			(end 0.120396 0.2794)
			(stroke
				(width 0.1)
				(type default)
			)
			(layer "F.Fab")
		)
		(fp_line
			(start 0.120396 0.2794)
			(end -0.12065 0.2794)
			(stroke
				(width 0.1)
				(type default)
			)
			(layer "F.Fab")
		)
		(fp_line
			(start -0.12065 0.3048)
			(end -0.67945 0.3048)
			(stroke
				(width 0.1)
				(type default)
			)
			(layer "F.Fab")
		)
		(fp_line
			(start -0.12065 0.2794)
			(end -0.12065 0.3048)
			(stroke
				(width 0.1)
				(type default)
			)
			(layer "F.Fab")
		)
		(fp_line
			(start -0.12065 -0.2794)
			(end 0.12065 -0.2794)
			(stroke
				(width 0.1)
				(type default)
			)
			(layer "F.Fab")
		)
		(fp_line
			(start -0.12065 -0.305054)
			(end -0.12065 -0.2794)
			(stroke
				(width 0.1)
				(type default)
			)
			(layer "F.Fab")
		)
		(fp_line
			(start -0.67945 0.3048)
			(end -0.67945 -0.305054)
			(stroke
				(width 0.1)
				(type default)
			)
			(layer "F.Fab")
		)
		(fp_line
			(start -0.67945 -0.305054)
			(end -0.12065 -0.305054)
			(stroke
				(width 0.1)
				(type default)
			)
			(layer "F.Fab")
		)
		(pad "1" smd circle
			(at -0.40005 0 180)
			(size 0 0)
			(layers "F.Cu" "F.Mask" "F.Paste")
			(net "GND")
		)
		(pad "2" smd circle
			(at 0.40005 0 180)
			(size 0 0)
			(layers "F.Cu" "F.Mask" "F.Paste")
			(net "INA230_1_A1")
		)
	)
	(footprint ""
		(layer "F.Cu")
		(at 52.877466 -25.309068 90)
		(property "Reference" "R3234"
			(at 0 0 90)
			(layer "F.SilkS")
			(hide yes)
			(effects
				(font
					(size 1.27 1.27)
				)
			)
		)
		(property "Value" ""
			(at 0 0 90)
			(layer "F.Fab")
			(effects
				(font
					(size 1.27 1.27)
				)
			)
		)
		(duplicate_pad_numbers_are_jumpers no)
		(fp_line
			(start 0.7874 -0.4064)
			(end 0.7874 0.4064)
			(stroke
				(width 0.1524)
				(type default)
			)
			(layer "F.SilkS")
		)
		(fp_line
			(start -0.7874 -0.4064)
			(end 0.7874 -0.4064)
			(stroke
				(width 0.1524)
				(type default)
			)
			(layer "F.SilkS")
		)
		(fp_line
			(start 0.7874 0.4064)
			(end -0.7874 0.4064)
			(stroke
				(width 0.1524)
				(type default)
			)
			(layer "F.SilkS")
		)
		(fp_line
			(start -0.7874 0.4064)
			(end -0.7874 -0.4064)
			(stroke
				(width 0.1524)
				(type default)
			)
			(layer "F.SilkS")
		)
		(fp_line
			(start -0.12065 -0.305054)
			(end -0.12065 -0.2794)
			(stroke
				(width 0.1)
				(type default)
			)
			(layer "F.Fab")
		)
		(fp_line
			(start -0.67945 -0.305054)
			(end -0.12065 -0.305054)
			(stroke
				(width 0.1)
				(type default)
			)
			(layer "F.Fab")
		)
		(fp_line
			(start 0.67945 -0.3048)
			(end 0.67945 0.3048)
			(stroke
				(width 0.1)
				(type default)
			)
			(layer "F.Fab")
		)
		(fp_line
			(start 0.12065 -0.3048)
			(end 0.67945 -0.3048)
			(stroke
				(width 0.1)
				(type default)
			)
			(layer "F.Fab")
		)
		(fp_line
			(start 0.12065 -0.2794)
			(end 0.12065 -0.3048)
			(stroke
				(width 0.1)
				(type default)
			)
			(layer "F.Fab")
		)
		(fp_line
			(start -0.12065 -0.2794)
			(end 0.12065 -0.2794)
			(stroke
				(width 0.1)
				(type default)
			)
			(layer "F.Fab")
		)
		(fp_line
			(start 0.120396 0.2794)
			(end -0.12065 0.2794)
			(stroke
				(width 0.1)
				(type default)
			)
			(layer "F.Fab")
		)
		(fp_line
			(start -0.12065 0.2794)
			(end -0.12065 0.3048)
			(stroke
				(width 0.1)
				(type default)
			)
			(layer "F.Fab")
		)
		(fp_line
			(start 0.67945 0.3048)
			(end 0.120396 0.3048)
			(stroke
				(width 0.1)
				(type default)
			)
			(layer "F.Fab")
		)
		(fp_line
			(start 0.120396 0.3048)
			(end 0.120396 0.2794)
			(stroke
				(width 0.1)
				(type default)
			)
			(layer "F.Fab")
		)
		(fp_line
			(start -0.12065 0.3048)
			(end -0.67945 0.3048)
			(stroke
				(width 0.1)
				(type default)
			)
			(layer "F.Fab")
		)
		(fp_line
			(start -0.67945 0.3048)
			(end -0.67945 -0.305054)
			(stroke
				(width 0.1)
				(type default)
			)
			(layer "F.Fab")
		)
		(pad "1" smd circle
			(at -0.40005 0 90)
			(size 0 0)
			(layers "F.Cu" "F.Mask" "F.Paste")
			(net "OCP_V3_2_AUX_PWR_EN")
		)
		(pad "2" smd circle
			(at 0.40005 0 90)
			(size 0 0)
			(layers "F.Cu" "F.Mask" "F.Paste")
			(net "OCP_V3_2_AUX_PWR_EN_R3")
		)
	)
	(footprint ""
		(layer "F.Cu")
		(at 271.800574 -93.927168 180)
		(property "Reference" "R1624"
			(at 0 0 180)
			(layer "F.SilkS")
			(hide yes)
			(effects
				(font
					(size 1.27 1.27)
				)
			)
		)
		(property "Value" ""
			(at 0 0 180)
			(layer "F.Fab")
			(effects
				(font
					(size 1.27 1.27)
				)
			)
		)
		(duplicate_pad_numbers_are_jumpers no)
		(fp_line
			(start 0.7874 0.4064)
			(end -0.7874 0.4064)
			(stroke
				(width 0.1524)
				(type default)
			)
			(layer "F.SilkS")
		)
		(fp_line
			(start 0.7874 -0.4064)
			(end 0.7874 0.4064)
			(stroke
				(width 0.1524)
				(type default)
			)
			(layer "F.SilkS")
		)
		(fp_line
			(start -0.7874 0.4064)
			(end -0.7874 -0.4064)
			(stroke
				(width 0.1524)
				(type default)
			)
			(layer "F.SilkS")
		)
		(fp_line
			(start -0.7874 -0.4064)
			(end 0.7874 -0.4064)
			(stroke
				(width 0.1524)
				(type default)
			)
			(layer "F.SilkS")
		)
		(fp_line
			(start 0.67945 0.3048)
			(end 0.120396 0.3048)
			(stroke
				(width 0.1)
				(type default)
			)
			(layer "F.Fab")
		)
		(fp_line
			(start 0.67945 -0.3048)
			(end 0.67945 0.3048)
			(stroke
				(width 0.1)
				(type default)
			)
			(layer "F.Fab")
		)
		(fp_line
			(start 0.12065 -0.2794)
			(end 0.12065 -0.3048)
			(stroke
				(width 0.1)
				(type default)
			)
			(layer "F.Fab")
		)
		(fp_line
			(start 0.12065 -0.3048)
			(end 0.67945 -0.3048)
			(stroke
				(width 0.1)
				(type default)
			)
			(layer "F.Fab")
		)
		(fp_line
			(start 0.120396 0.3048)
			(end 0.120396 0.2794)
			(stroke
				(width 0.1)
				(type default)
			)
			(layer "F.Fab")
		)
		(fp_line
			(start 0.120396 0.2794)
			(end -0.12065 0.2794)
			(stroke
				(width 0.1)
				(type default)
			)
			(layer "F.Fab")
		)
		(fp_line
			(start -0.12065 0.3048)
			(end -0.67945 0.3048)
			(stroke
				(width 0.1)
				(type default)
			)
			(layer "F.Fab")
		)
		(fp_line
			(start -0.12065 0.2794)
			(end -0.12065 0.3048)
			(stroke
				(width 0.1)
				(type default)
			)
			(layer "F.Fab")
		)
		(fp_line
			(start -0.12065 -0.2794)
			(end 0.12065 -0.2794)
			(stroke
				(width 0.1)
				(type default)
			)
			(layer "F.Fab")
		)
		(fp_line
			(start -0.12065 -0.305054)
			(end -0.12065 -0.2794)
			(stroke
				(width 0.1)
				(type default)
			)
			(layer "F.Fab")
		)
		(fp_line
			(start -0.67945 0.3048)
			(end -0.67945 -0.305054)
			(stroke
				(width 0.1)
				(type default)
			)
			(layer "F.Fab")
		)
		(fp_line
			(start -0.67945 -0.305054)
			(end -0.12065 -0.305054)
			(stroke
				(width 0.1)
				(type default)
			)
			(layer "F.Fab")
		)
		(pad "1" smd circle
			(at -0.40005 0 180)
			(size 0 0)
			(layers "F.Cu" "F.Mask" "F.Paste")
			(net "PVDD18_S5_P0")
		)
		(pad "2" smd circle
			(at 0.40005 0 180)
			(size 0 0)
			(layers "F.Cu" "F.Mask" "F.Paste")
			(net "HDT_HDR_TCK")
		)
	)
	(footprint ""
		(layer "F.Cu")
		(at 110.140496 -150.941786 90)
		(property "Reference" "PC336"
			(at 4.185666 -0.65151 0)
			(unlocked yes)
			(layer "F.SilkS")
			(effects
				(font
					(size 0.7874 0.5842)
					(thickness 0.1524)
				)
				(justify left)
			)
		)
		(property "Value" ""
			(at 0 0 90)
			(layer "F.Fab")
			(effects
				(font
					(size 1.27 1.27)
				)
			)
		)
		(duplicate_pad_numbers_are_jumpers no)
		(fp_line
			(start -3.400044 1.249934)
			(end 3.400044 1.249934)
			(stroke
				(width 0.1524)
				(type default)
			)
			(layer "F.SilkS")
		)
		(fp_circle
			(center 0 1.249934)
			(end 0 4.649978)
			(stroke
				(width 0.1524)
				(type default)
			)
			(fill no)
			(layer "F.SilkS")
		)
		(fp_poly
			(pts
				(arc
					(start 3.400044 1.249934)
					(mid 0 4.649978)
					(end -3.400044 1.249934)
				)
			)
			(stroke
				(width 0)
				(type default)
			)
			(fill yes)
			(layer "F.SilkS")
		)
		(fp_circle
			(center 0 1.249934)
			(end 0 4.649978)
			(stroke
				(width 0.1)
				(type default)
			)
			(fill no)
			(layer "F.Fab")
		)
		(pad "1" thru_hole rect
			(at 0 0 90)
			(size 1.524 1.524)
			(drill 1.016)
			(layers "*.Cu" "*.Mask")
			(remove_unused_layers no)
			(net "SW_P12V_AUX_PVDDCR_SOC_P1_FLT")
			(clearance 0)
			(padstack
				(mode front_inner_back)
				(layer "Inner"
					(shape circle)
					(size 1.524 1.524)
					(clearance 0)
				)
				(layer "B.Cu"
					(shape rect)
					(size 1.524 1.524)
					(clearance 0)
				)
			)
		)
		(pad "2" thru_hole circle
			(at 0 2.500122 90)
			(size 1.524 1.524)
			(drill 1.016)
			(layers "*.Cu" "*.Mask")
			(remove_unused_layers no)
			(net "GND")
			(clearance 0)
		)
	)
	(footprint ""
		(layer "F.Cu")
		(at 425.163488 -109.12983 90)
		(property "Reference" "PC2091"
			(at 0 0 90)
			(layer "F.SilkS")
			(hide yes)
			(effects
				(font
					(size 1.27 1.27)
				)
			)
		)
		(property "Value" ""
			(at 0 0 90)
			(layer "F.Fab")
			(effects
				(font
					(size 1.27 1.27)
				)
			)
		)
		(duplicate_pad_numbers_are_jumpers no)
		(fp_line
			(start 0.7874 -0.4064)
			(end 0.7874 0.4064)
			(stroke
				(width 0.1524)
				(type default)
			)
			(layer "F.SilkS")
		)
		(fp_line
			(start -0.7874 -0.4064)
			(end 0.7874 -0.4064)
			(stroke
				(width 0.1524)
				(type default)
			)
			(layer "F.SilkS")
		)
		(fp_line
			(start 0.7874 0.4064)
			(end -0.7874 0.4064)
			(stroke
				(width 0.1524)
				(type default)
			)
			(layer "F.SilkS")
		)
		(fp_line
			(start -0.7874 0.4064)
			(end -0.7874 -0.4064)
			(stroke
				(width 0.1524)
				(type default)
			)
			(layer "F.SilkS")
		)
		(fp_line
			(start -0.12065 -0.305054)
			(end -0.12065 -0.2794)
			(stroke
				(width 0.1)
				(type default)
			)
			(layer "F.Fab")
		)
		(fp_line
			(start -0.67945 -0.305054)
			(end -0.12065 -0.305054)
			(stroke
				(width 0.1)
				(type default)
			)
			(layer "F.Fab")
		)
		(fp_line
			(start 0.67945 -0.3048)
			(end 0.67945 0.3048)
			(stroke
				(width 0.1)
				(type default)
			)
			(layer "F.Fab")
		)
		(fp_line
			(start 0.12065 -0.3048)
			(end 0.67945 -0.3048)
			(stroke
				(width 0.1)
				(type default)
			)
			(layer "F.Fab")
		)
		(fp_line
			(start 0.12065 -0.2794)
			(end 0.12065 -0.3048)
			(stroke
				(width 0.1)
				(type default)
			)
			(layer "F.Fab")
		)
		(fp_line
			(start -0.12065 -0.2794)
			(end 0.12065 -0.2794)
			(stroke
				(width 0.1)
				(type default)
			)
			(layer "F.Fab")
		)
		(fp_line
			(start 0.120396 0.2794)
			(end -0.12065 0.2794)
			(stroke
				(width 0.1)
				(type default)
			)
			(layer "F.Fab")
		)
		(fp_line
			(start -0.12065 0.2794)
			(end -0.12065 0.3048)
			(stroke
				(width 0.1)
				(type default)
			)
			(layer "F.Fab")
		)
		(fp_line
			(start 0.67945 0.3048)
			(end 0.120396 0.3048)
			(stroke
				(width 0.1)
				(type default)
			)
			(layer "F.Fab")
		)
		(fp_line
			(start 0.120396 0.3048)
			(end 0.120396 0.2794)
			(stroke
				(width 0.1)
				(type default)
			)
			(layer "F.Fab")
		)
		(fp_line
			(start -0.12065 0.3048)
			(end -0.67945 0.3048)
			(stroke
				(width 0.1)
				(type default)
			)
			(layer "F.Fab")
		)
		(fp_line
			(start -0.67945 0.3048)
			(end -0.67945 -0.305054)
			(stroke
				(width 0.1)
				(type default)
			)
			(layer "F.Fab")
		)
		(pad "1" smd circle
			(at -0.40005 0 90)
			(size 0 0)
			(layers "F.Cu" "F.Mask" "F.Paste")
			(net "P3V3_OCP_SFF_R")
		)
		(pad "2" smd circle
			(at 0.40005 0 90)
			(size 0 0)
			(layers "F.Cu" "F.Mask" "F.Paste")
			(net "GND")
		)
	)
)
